(kicad_pcb
	(version 20260206)
	(generator "pcbnew")
	(generator_version "10.0")
	(general
		(thickness 1.6)
		(legacy_teardrops no)
	)
	(paper "A4")
	(title_block
		(title "v1-chassis-manager — T6M_CM_d_v01_1031_1645.brd")
		(comment 1 "Open CloudServer (Microsoft) / footprints 1512-1522 of 2512")
	)
	(layers
		(0 "F.Cu" signal "TOP")
		(4 "In1.Cu" signal "GND1")
		(6 "In2.Cu" signal "IN1")
		(8 "In3.Cu" signal "VCC1")
		(10 "In4.Cu" signal "VCC2")
		(12 "In5.Cu" signal "GND2")
		(14 "In6.Cu" signal "IN2")
		(16 "In7.Cu" signal "IN3")
		(18 "In8.Cu" signal "GND3")
		(2 "B.Cu" signal "BOTTOM")
		(9 "F.Adhes" user "F.Adhesive")
		(11 "B.Adhes" user "B.Adhesive")
		(13 "F.Paste" user "Package Geometry/Pastemask Top")
		(15 "B.Paste" user "Package Geometry/Pastemask Bottom")
		(5 "F.SilkS" user "Ref Des/Silkscreen Top")
		(7 "B.SilkS" user "Ref Des/Silkscreen Bottom")
		(1 "F.Mask" user "Board Geometry/Soldermask Top")
		(3 "B.Mask" user "Board Geometry/Soldermask Bottom")
		(17 "Dwgs.User" user "User.Drawings")
		(19 "Cmts.User" user "User.Comments")
		(21 "Eco1.User" user "User.Eco1")
		(23 "Eco2.User" user "User.Eco2")
		(25 "Edge.Cuts" user "Board Geometry/Outline")
		(27 "Margin" user)
		(31 "F.CrtYd" user "Package Geometry/Place Bound Top")
		(29 "B.CrtYd" user "Package Geometry/Place Bound Bottom")
		(35 "F.Fab" user "Ref Des/Assembly Top")
		(33 "B.Fab" user "Ref Des/Assembly Bottom")
	)
	(footprint ""
		(layer "F.Cu")
		(at 106.170476 -164.769546 180)
		(property "Reference" "R772"
			(at -85.286342 -69.739764 0)
			(unlocked yes)
			(layer "F.SilkS")
			(effects
				(font
					(size 0.7874 0.5842)
					(thickness 0.1524)
				)
				(justify left)
			)
		)
		(property "Value" ""
			(at 0 0 180)
			(layer "F.Fab")
			(effects
				(font
					(size 1.27 1.27)
				)
			)
		)
		(duplicate_pad_numbers_are_jumpers no)
		(fp_line
			(start 0.7874 0.4064)
			(end -0.7874 0.4064)
			(stroke
				(width 0.1524)
				(type default)
			)
			(layer "F.SilkS")
		)
		(fp_line
			(start 0.7874 -0.4064)
			(end 0.7874 0.4064)
			(stroke
				(width 0.1524)
				(type default)
			)
			(layer "F.SilkS")
		)
		(fp_line
			(start -0.7874 0.4064)
			(end -0.7874 -0.4064)
			(stroke
				(width 0.1524)
				(type default)
			)
			(layer "F.SilkS")
		)
		(fp_line
			(start -0.7874 -0.4064)
			(end 0.7874 -0.4064)
			(stroke
				(width 0.1524)
				(type default)
			)
			(layer "F.SilkS")
		)
		(fp_poly
			(pts
				(xy -0.508 0.2794) (xy -0.508 0.2286) (xy -0.635 0.2286) (xy -0.635 -0.254) (xy -0.5334 -0.254)
				(xy -0.5334 -0.2794) (xy 0.5334 -0.2794) (xy 0.5334 -0.254) (xy 0.635 -0.254) (xy 0.635 0.254) (xy 0.5334 0.254)
				(xy 0.5334 0.2794)
			)
			(stroke
				(width 0)
				(type default)
			)
			(fill no)
			(layer "F.CrtYd")
		)
		(pad "1" smd rect
			(at 0.40005 0 180)
			(size 0.4572 0.508)
			(layers "F.Cu" "F.Mask" "F.Paste")
			(net "FNACTRL2_ADD")
		)
		(pad "2" smd rect
			(at -0.40005 0 180)
			(size 0.4572 0.508)
			(layers "F.Cu" "F.Mask" "F.Paste")
			(net "GND")
		)
	)
	(footprint ""
		(layer "F.Cu")
		(at 106.116374 -174.67961 -90)
		(property "Reference" "R765"
			(at -2.00787 1.077468 90)
			(unlocked yes)
			(layer "F.SilkS")
			(effects
				(font
					(size 0.7874 0.5842)
					(thickness 0.1524)
				)
				(justify left)
			)
		)
		(property "Value" ""
			(at 0 0 270)
			(layer "F.Fab")
			(effects
				(font
					(size 1.27 1.27)
				)
			)
		)
		(duplicate_pad_numbers_are_jumpers no)
		(fp_line
			(start -0.7874 0.4064)
			(end -0.7874 -0.4064)
			(stroke
				(width 0.1524)
				(type default)
			)
			(layer "F.SilkS")
		)
		(fp_line
			(start 0.7874 0.4064)
			(end -0.7874 0.4064)
			(stroke
				(width 0.1524)
				(type default)
			)
			(layer "F.SilkS")
		)
		(fp_line
			(start -0.7874 -0.4064)
			(end 0.7874 -0.4064)
			(stroke
				(width 0.1524)
				(type default)
			)
			(layer "F.SilkS")
		)
		(fp_line
			(start 0.7874 -0.4064)
			(end 0.7874 0.4064)
			(stroke
				(width 0.1524)
				(type default)
			)
			(layer "F.SilkS")
		)
		(fp_poly
			(pts
				(xy -0.508 0.2794) (xy -0.508 0.2286) (xy -0.635 0.2286) (xy -0.635 -0.254) (xy -0.5334 -0.254)
				(xy -0.5334 -0.2794) (xy 0.5334 -0.2794) (xy 0.5334 -0.254) (xy 0.635 -0.254) (xy 0.635 0.254) (xy 0.5334 0.254)
				(xy 0.5334 0.2794)
			)
			(stroke
				(width 0)
				(type default)
			)
			(fill no)
			(layer "F.CrtYd")
		)
		(pad "1" smd rect
			(at 0.40005 0 270)
			(size 0.4572 0.508)
			(layers "F.Cu" "F.Mask" "F.Paste")
			(net "I2C_SDA_FANCTRL1_R")
		)
		(pad "2" smd rect
			(at -0.40005 0 270)
			(size 0.4572 0.508)
			(layers "F.Cu" "F.Mask" "F.Paste")
			(net "I2C_COM3_SDA")
		)
	)
	(footprint ""
		(layer "F.Cu")
		(at 30.498288 -122.131582 90)
		(property "Reference" "C828"
			(at -2.965958 -2.225294 90)
			(unlocked yes)
			(layer "F.SilkS")
			(effects
				(font
					(size 0.7874 0.5842)
					(thickness 0.1524)
				)
				(justify left)
			)
		)
		(property "Value" ""
			(at 0 0 90)
			(layer "F.Fab")
			(effects
				(font
					(size 1.27 1.27)
				)
			)
		)
		(duplicate_pad_numbers_are_jumpers no)
		(fp_line
			(start 1.905 -0.8636)
			(end 1.905 0.8636)
			(stroke
				(width 0.1524)
				(type default)
			)
			(layer "F.SilkS")
		)
		(fp_line
			(start -1.905 -0.8636)
			(end 1.905 -0.8636)
			(stroke
				(width 0.1524)
				(type default)
			)
			(layer "F.SilkS")
		)
		(fp_line
			(start 0 0.8382)
			(end 0 -0.8382)
			(stroke
				(width 0.1524)
				(type default)
			)
			(layer "F.SilkS")
		)
		(fp_line
			(start 1.905 0.8636)
			(end -1.905 0.8636)
			(stroke
				(width 0.1524)
				(type default)
			)
			(layer "F.SilkS")
		)
		(fp_line
			(start -1.905 0.8636)
			(end -1.905 -0.8636)
			(stroke
				(width 0.1524)
				(type default)
			)
			(layer "F.SilkS")
		)
		(fp_rect
			(start -1.524 0.7366)
			(end 1.524 -0.7366)
			(stroke
				(width 0)
				(type default)
			)
			(fill no)
			(layer "F.CrtYd")
		)
		(pad "1" smd rect
			(at 0.94996 0 90)
			(size 1.1176 1.3716)
			(layers "F.Cu" "F.Mask" "F.Paste")
			(net "P1V8_NODE1")
		)
		(pad "2" smd rect
			(at -0.94996 0 90)
			(size 1.1176 1.3716)
			(layers "F.Cu" "F.Mask" "F.Paste")
			(net "GND")
		)
	)
	(footprint ""
		(layer "F.Cu")
		(at 15.061946 -134.017512 -90)
		(property "Reference" "PC70"
			(at -0.993648 0.04699 90)
			(unlocked yes)
			(layer "F.SilkS")
			(effects
				(font
					(size 0.7874 0.5842)
					(thickness 0.1524)
				)
				(justify left)
			)
		)
		(property "Value" ""
			(at 0 0 270)
			(layer "F.Fab")
			(effects
				(font
					(size 1.27 1.27)
				)
			)
		)
		(duplicate_pad_numbers_are_jumpers no)
		(fp_line
			(start -0.7874 0.4064)
			(end -0.7874 -0.4064)
			(stroke
				(width 0.1524)
				(type default)
			)
			(layer "F.SilkS")
		)
		(fp_line
			(start 0.7874 0.4064)
			(end -0.7874 0.4064)
			(stroke
				(width 0.1524)
				(type default)
			)
			(layer "F.SilkS")
		)
		(fp_line
			(start 0 0.381)
			(end 0 -0.381)
			(stroke
				(width 0.1524)
				(type default)
			)
			(layer "F.SilkS")
		)
		(fp_line
			(start -0.7874 -0.4064)
			(end 0.7874 -0.4064)
			(stroke
				(width 0.1524)
				(type default)
			)
			(layer "F.SilkS")
		)
		(fp_line
			(start 0.7874 -0.4064)
			(end 0.7874 0.4064)
			(stroke
				(width 0.1524)
				(type default)
			)
			(layer "F.SilkS")
		)
		(fp_poly
			(pts
				(xy -0.5334 0.254) (xy -0.635 0.254) (xy -0.635 0.2286) (xy -0.635 -0.254) (xy -0.5334 -0.254) (xy -0.5334 -0.2794)
				(xy 0.5334 -0.2794) (xy 0.5334 -0.254) (xy 0.635 -0.254) (xy 0.635 0.254) (xy 0.5334 0.254) (xy 0.5334 0.2794)
				(xy -0.508 0.2794) (xy -0.5334 0.2794)
			)
			(stroke
				(width 0)
				(type default)
			)
			(fill no)
			(layer "F.CrtYd")
		)
		(pad "1" smd rect
			(at 0.40005 0 270)
			(size 0.4572 0.508)
			(layers "F.Cu" "F.Mask" "F.Paste")
			(net "P1V05_NODE1_VSNS")
		)
		(pad "2" smd rect
			(at -0.40005 0 270)
			(size 0.4572 0.508)
			(layers "F.Cu" "F.Mask" "F.Paste")
			(net "GND")
		)
	)
	(footprint ""
		(layer "F.Cu")
		(at 94.451932 -165.139624)
		(property "Reference" "R768"
			(at 86.63305 73.147936 0)
			(unlocked yes)
			(layer "F.SilkS")
			(effects
				(font
					(size 0.7874 0.5842)
					(thickness 0.1524)
				)
				(justify left)
			)
		)
		(property "Value" ""
			(at 0 0 0)
			(layer "F.Fab")
			(effects
				(font
					(size 1.27 1.27)
				)
			)
		)
		(duplicate_pad_numbers_are_jumpers no)
		(fp_line
			(start -0.7874 -0.4064)
			(end 0.7874 -0.4064)
			(stroke
				(width 0.1524)
				(type default)
			)
			(layer "F.SilkS")
		)
		(fp_line
			(start -0.7874 0.4064)
			(end -0.7874 -0.4064)
			(stroke
				(width 0.1524)
				(type default)
			)
			(layer "F.SilkS")
		)
		(fp_line
			(start 0.7874 -0.4064)
			(end 0.7874 0.4064)
			(stroke
				(width 0.1524)
				(type default)
			)
			(layer "F.SilkS")
		)
		(fp_line
			(start 0.7874 0.4064)
			(end -0.7874 0.4064)
			(stroke
				(width 0.1524)
				(type default)
			)
			(layer "F.SilkS")
		)
		(fp_poly
			(pts
				(xy -0.508 0.2794) (xy -0.508 0.2286) (xy -0.635 0.2286) (xy -0.635 -0.254) (xy -0.5334 -0.254)
				(xy -0.5334 -0.2794) (xy 0.5334 -0.2794) (xy 0.5334 -0.254) (xy 0.635 -0.254) (xy 0.635 0.254) (xy 0.5334 0.254)
				(xy 0.5334 0.2794)
			)
			(stroke
				(width 0)
				(type default)
			)
			(fill no)
			(layer "F.CrtYd")
		)
		(pad "1" smd rect
			(at 0.40005 0)
			(size 0.4572 0.508)
			(layers "F.Cu" "F.Mask" "F.Paste")
			(net "FAN5_TACH_IN")
		)
		(pad "2" smd rect
			(at -0.40005 0)
			(size 0.4572 0.508)
			(layers "F.Cu" "F.Mask" "F.Paste")
			(net "FAN5_TACH")
		)
	)
	(footprint ""
		(layer "F.Cu")
		(at 35.243008 -186.620404)
		(property "Reference" "C768"
			(at -1.53162 -5.211064 0)
			(unlocked yes)
			(layer "F.SilkS")
			(effects
				(font
					(size 0.7874 0.5842)
					(thickness 0.1524)
				)
				(justify left)
			)
		)
		(property "Value" ""
			(at 0 0 0)
			(layer "F.Fab")
			(effects
				(font
					(size 1.27 1.27)
				)
			)
		)
		(duplicate_pad_numbers_are_jumpers no)
		(fp_line
			(start -0.7874 -0.4064)
			(end 0.7874 -0.4064)
			(stroke
				(width 0.1524)
				(type default)
			)
			(layer "F.SilkS")
		)
		(fp_line
			(start -0.7874 0.4064)
			(end -0.7874 -0.4064)
			(stroke
				(width 0.1524)
				(type default)
			)
			(layer "F.SilkS")
		)
		(fp_line
			(start 0 0.381)
			(end 0 -0.381)
			(stroke
				(width 0.1524)
				(type default)
			)
			(layer "F.SilkS")
		)
		(fp_line
			(start 0.7874 -0.4064)
			(end 0.7874 0.4064)
			(stroke
				(width 0.1524)
				(type default)
			)
			(layer "F.SilkS")
		)
		(fp_line
			(start 0.7874 0.4064)
			(end -0.7874 0.4064)
			(stroke
				(width 0.1524)
				(type default)
			)
			(layer "F.SilkS")
		)
		(fp_poly
			(pts
				(xy -0.5334 0.254) (xy -0.635 0.254) (xy -0.635 0.2286) (xy -0.635 -0.254) (xy -0.5334 -0.254) (xy -0.5334 -0.2794)
				(xy 0.5334 -0.2794) (xy 0.5334 -0.254) (xy 0.635 -0.254) (xy 0.635 0.254) (xy 0.5334 0.254) (xy 0.5334 0.2794)
				(xy -0.508 0.2794) (xy -0.5334 0.2794)
			)
			(stroke
				(width 0)
				(type default)
			)
			(fill no)
			(layer "F.CrtYd")
		)
		(pad "1" smd rect
			(at 0.40005 0)
			(size 0.4572 0.508)
			(layers "F.Cu" "F.Mask" "F.Paste")
			(net "P12V_PDB")
		)
		(pad "2" smd rect
			(at -0.40005 0)
			(size 0.4572 0.508)
			(layers "F.Cu" "F.Mask" "F.Paste")
			(net "GND")
		)
	)
	(footprint ""
		(layer "F.Cu")
		(at 157.58668 -101.105208 180)
		(property "Reference" "C364"
			(at 1.524 -2.075688 0)
			(unlocked yes)
			(layer "F.SilkS")
			(effects
				(font
					(size 0.7874 0.5842)
					(thickness 0.1524)
				)
				(justify left)
			)
		)
		(property "Value" ""
			(at 0 0 180)
			(layer "F.Fab")
			(effects
				(font
					(size 1.27 1.27)
				)
			)
		)
		(duplicate_pad_numbers_are_jumpers no)
		(fp_line
			(start 0.7874 0.4064)
			(end -0.7874 0.4064)
			(stroke
				(width 0.1524)
				(type default)
			)
			(layer "F.SilkS")
		)
		(fp_line
			(start 0.7874 -0.4064)
			(end 0.7874 0.4064)
			(stroke
				(width 0.1524)
				(type default)
			)
			(layer "F.SilkS")
		)
		(fp_line
			(start 0 0.381)
			(end 0 -0.381)
			(stroke
				(width 0.1524)
				(type default)
			)
			(layer "F.SilkS")
		)
		(fp_line
			(start -0.7874 0.4064)
			(end -0.7874 -0.4064)
			(stroke
				(width 0.1524)
				(type default)
			)
			(layer "F.SilkS")
		)
		(fp_line
			(start -0.7874 -0.4064)
			(end 0.7874 -0.4064)
			(stroke
				(width 0.1524)
				(type default)
			)
			(layer "F.SilkS")
		)
		(fp_poly
			(pts
				(xy -0.5334 0.254) (xy -0.635 0.254) (xy -0.635 0.2286) (xy -0.635 -0.254) (xy -0.5334 -0.254) (xy -0.5334 -0.2794)
				(xy 0.5334 -0.2794) (xy 0.5334 -0.254) (xy 0.635 -0.254) (xy 0.635 0.254) (xy 0.5334 0.254) (xy 0.5334 0.2794)
				(xy -0.508 0.2794) (xy -0.5334 0.2794)
			)
			(stroke
				(width 0)
				(type default)
			)
			(fill no)
			(layer "F.CrtYd")
		)
		(pad "1" smd rect
			(at 0.40005 0 180)
			(size 0.4572 0.508)
			(layers "F.Cu" "F.Mask" "F.Paste")
			(net "P2E_CPU_USB_NODE1_RX_DN")
		)
		(pad "2" smd rect
			(at -0.40005 0 180)
			(size 0.4572 0.508)
			(layers "F.Cu" "F.Mask" "F.Paste")
			(net "P2E_CPU_USB_NODE1_RX_C_DN")
		)
	)
	(footprint ""
		(layer "F.Cu")
		(at 147.245578 -57.249822 -90)
		(property "Reference" "R515"
			(at -14.50213 -26.0858 90)
			(unlocked yes)
			(layer "F.SilkS")
			(effects
				(font
					(size 0.7874 0.5842)
					(thickness 0.1524)
				)
				(justify left)
			)
		)
		(property "Value" ""
			(at 0 0 270)
			(layer "F.Fab")
			(effects
				(font
					(size 1.27 1.27)
				)
			)
		)
		(duplicate_pad_numbers_are_jumpers no)
		(fp_line
			(start -0.7874 0.4064)
			(end -0.7874 -0.4064)
			(stroke
				(width 0.1524)
				(type default)
			)
			(layer "F.SilkS")
		)
		(fp_line
			(start 0.7874 0.4064)
			(end -0.7874 0.4064)
			(stroke
				(width 0.1524)
				(type default)
			)
			(layer "F.SilkS")
		)
		(fp_line
			(start -0.7874 -0.4064)
			(end 0.7874 -0.4064)
			(stroke
				(width 0.1524)
				(type default)
			)
			(layer "F.SilkS")
		)
		(fp_line
			(start 0.7874 -0.4064)
			(end 0.7874 0.4064)
			(stroke
				(width 0.1524)
				(type default)
			)
			(layer "F.SilkS")
		)
		(fp_poly
			(pts
				(xy -0.508 0.2794) (xy -0.508 0.2286) (xy -0.635 0.2286) (xy -0.635 -0.254) (xy -0.5334 -0.254)
				(xy -0.5334 -0.2794) (xy 0.5334 -0.2794) (xy 0.5334 -0.254) (xy 0.635 -0.254) (xy 0.635 0.254) (xy 0.5334 0.254)
				(xy 0.5334 0.2794)
			)
			(stroke
				(width 0)
				(type default)
			)
			(fill no)
			(layer "F.CrtYd")
		)
		(pad "1" smd rect
			(at 0.40005 0 270)
			(size 0.4572 0.508)
			(layers "F.Cu" "F.Mask" "F.Paste")
			(net "GND")
		)
		(pad "2" smd rect
			(at -0.40005 0 270)
			(size 0.4572 0.508)
			(layers "F.Cu" "F.Mask" "F.Paste")
			(net "SATA_NODE1_GPIO3")
		)
	)
	(footprint ""
		(layer "F.Cu")
		(at 16.552926 -46.315884 -90)
		(property "Reference" "R639"
			(at 8.57885 0.929386 90)
			(unlocked yes)
			(layer "F.SilkS")
			(effects
				(font
					(size 0.7874 0.5842)
					(thickness 0.1524)
				)
				(justify left)
			)
		)
		(property "Value" ""
			(at 0 0 270)
			(layer "F.Fab")
			(effects
				(font
					(size 1.27 1.27)
				)
			)
		)
		(duplicate_pad_numbers_are_jumpers no)
		(fp_line
			(start -0.7874 0.4064)
			(end -0.7874 -0.4064)
			(stroke
				(width 0.1524)
				(type default)
			)
			(layer "F.SilkS")
		)
		(fp_line
			(start 0.7874 0.4064)
			(end -0.7874 0.4064)
			(stroke
				(width 0.1524)
				(type default)
			)
			(layer "F.SilkS")
		)
		(fp_line
			(start -0.7874 -0.4064)
			(end 0.7874 -0.4064)
			(stroke
				(width 0.1524)
				(type default)
			)
			(layer "F.SilkS")
		)
		(fp_line
			(start 0.7874 -0.4064)
			(end 0.7874 0.4064)
			(stroke
				(width 0.1524)
				(type default)
			)
			(layer "F.SilkS")
		)
		(fp_poly
			(pts
				(xy -0.508 0.2794) (xy -0.508 0.2286) (xy -0.635 0.2286) (xy -0.635 -0.254) (xy -0.5334 -0.254)
				(xy -0.5334 -0.2794) (xy 0.5334 -0.2794) (xy 0.5334 -0.254) (xy 0.635 -0.254) (xy 0.635 0.254) (xy 0.5334 0.254)
				(xy 0.5334 0.2794)
			)
			(stroke
				(width 0)
				(type default)
			)
			(fill no)
			(layer "F.CrtYd")
		)
		(pad "1" smd rect
			(at 0.40005 0 270)
			(size 0.4572 0.508)
			(layers "F.Cu" "F.Mask" "F.Paste")
			(net "I2C_VIDREAR_5V_SDA")
		)
		(pad "2" smd rect
			(at -0.40005 0 270)
			(size 0.4572 0.508)
			(layers "F.Cu" "F.Mask" "F.Paste")
			(net "CRT_DDCDATA")
		)
	)
	(footprint ""
		(layer "F.Cu")
		(at 120.63476 -175.426624 90)
		(property "Reference" "R796"
			(at -57.011316 32.536638 90)
			(unlocked yes)
			(layer "F.SilkS")
			(effects
				(font
					(size 0.7874 0.5842)
					(thickness 0.1524)
				)
				(justify left)
			)
		)
		(property "Value" ""
			(at 0 0 90)
			(layer "F.Fab")
			(effects
				(font
					(size 1.27 1.27)
				)
			)
		)
		(duplicate_pad_numbers_are_jumpers no)
		(fp_line
			(start 0.7874 -0.4064)
			(end 0.7874 0.4064)
			(stroke
				(width 0.1524)
				(type default)
			)
			(layer "F.SilkS")
		)
		(fp_line
			(start -0.7874 -0.4064)
			(end 0.7874 -0.4064)
			(stroke
				(width 0.1524)
				(type default)
			)
			(layer "F.SilkS")
		)
		(fp_line
			(start 0.7874 0.4064)
			(end -0.7874 0.4064)
			(stroke
				(width 0.1524)
				(type default)
			)
			(layer "F.SilkS")
		)
		(fp_line
			(start -0.7874 0.4064)
			(end -0.7874 -0.4064)
			(stroke
				(width 0.1524)
				(type default)
			)
			(layer "F.SilkS")
		)
		(fp_poly
			(pts
				(xy -0.508 0.2794) (xy -0.508 0.2286) (xy -0.635 0.2286) (xy -0.635 -0.254) (xy -0.5334 -0.254)
				(xy -0.5334 -0.2794) (xy 0.5334 -0.2794) (xy 0.5334 -0.254) (xy 0.635 -0.254) (xy 0.635 0.254) (xy 0.5334 0.254)
				(xy 0.5334 0.2794)
			)
			(stroke
				(width 0)
				(type default)
			)
			(fill no)
			(layer "F.CrtYd")
		)
		(pad "1" smd rect
			(at 0.40005 0 90)
			(size 0.4572 0.508)
			(layers "F.Cu" "F.Mask" "F.Paste")
			(net "N31328106")
		)
		(pad "2" smd rect
			(at -0.40005 0 90)
			(size 0.4572 0.508)
			(layers "F.Cu" "F.Mask" "F.Paste")
			(net "GND")
		)
	)
	(footprint ""
		(layer "F.Cu")
		(at 165.464998 -145.83283 -90)
		(property "Reference" "R589"
			(at -1.064768 2.666238 0)
			(unlocked yes)
			(layer "F.SilkS")
			(effects
				(font
					(size 0.635 0.4064)
					(thickness 0.1524)
				)
				(justify left)
			)
		)
		(property "Value" ""
			(at 0 0 270)
			(layer "F.Fab")
			(effects
				(font
					(size 1.27 1.27)
				)
			)
		)
		(duplicate_pad_numbers_are_jumpers no)
		(fp_line
			(start -0.7874 0.4064)
			(end -0.7874 -0.4064)
			(stroke
				(width 0.1524)
				(type default)
			)
			(layer "F.SilkS")
		)
		(fp_line
			(start 0.7874 0.4064)
			(end -0.7874 0.4064)
			(stroke
				(width 0.1524)
				(type default)
			)
			(layer "F.SilkS")
		)
		(fp_line
			(start -0.7874 -0.4064)
			(end 0.7874 -0.4064)
			(stroke
				(width 0.1524)
				(type default)
			)
			(layer "F.SilkS")
		)
		(fp_line
			(start 0.7874 -0.4064)
			(end 0.7874 0.4064)
			(stroke
				(width 0.1524)
				(type default)
			)
			(layer "F.SilkS")
		)
		(fp_poly
			(pts
				(xy -0.508 0.2794) (xy -0.508 0.2286) (xy -0.635 0.2286) (xy -0.635 -0.254) (xy -0.5334 -0.254)
				(xy -0.5334 -0.2794) (xy 0.5334 -0.2794) (xy 0.5334 -0.254) (xy 0.635 -0.254) (xy 0.635 0.254) (xy 0.5334 0.254)
				(xy 0.5334 0.2794)
			)
			(stroke
				(width 0)
				(type default)
			)
			(fill no)
			(layer "F.CrtYd")
		)
		(pad "1" smd rect
			(at 0.40005 0 270)
			(size 0.4572 0.508)
			(layers "F.Cu" "F.Mask" "F.Paste")
			(net "GND")
		)
		(pad "2" smd rect
			(at -0.40005 0 270)
			(size 0.4572 0.508)
			(layers "F.Cu" "F.Mask" "F.Paste")
			(net "LAN2_RST")
		)
	)
)
